(kicad_pcb
	(version 20260206)
	(generator "pcbnew")
	(generator_version "10.0")
	(general
		(thickness 1.6)
		(legacy_teardrops no)
	)
	(paper "A4")
	(title_block
		(title "9052_F0T_PDB_Converter_Brick_F_V03_1208_1600_OCP.brd")
		(comment 1 "Grand Teton / footprints 1-7 of 578")
	)
	(layers
		(0 "F.Cu" signal "TOP")
		(4 "In1.Cu" signal "GND")
		(6 "In2.Cu" signal "IN1")
		(8 "In3.Cu" signal "GND1")
		(10 "In4.Cu" signal "VCC")
		(12 "In5.Cu" signal "VCC1")
		(14 "In6.Cu" signal "GND2")
		(16 "In7.Cu" signal "IN2")
		(18 "In8.Cu" signal "GND3")
		(2 "B.Cu" signal "BOTTOM")
		(9 "F.Adhes" user "F.Adhesive")
		(11 "B.Adhes" user "B.Adhesive")
		(13 "F.Paste" user "Package Geometry/Pastemask Top")
		(15 "B.Paste" user "Package Geometry/Pastemask Bottom")
		(5 "F.SilkS" user "Ref Des/Silkscreen Top")
		(7 "B.SilkS" user "Ref Des/Silkscreen Bottom")
		(1 "F.Mask" user "Board Geometry/Soldermask Top")
		(3 "B.Mask" user "Board Geometry/Soldermask Bottom")
		(17 "Dwgs.User" user "User.Drawings")
		(19 "Cmts.User" user "User.Comments")
		(21 "Eco1.User" user "User.Eco1")
		(23 "Eco2.User" user "User.Eco2")
		(25 "Edge.Cuts" user "Board Geometry/Outline")
		(27 "Margin" user)
		(31 "F.CrtYd" user "Package Geometry/Place Bound Top")
		(29 "B.CrtYd" user "Package Geometry/Place Bound Bottom")
		(35 "F.Fab" user "Ref Des/Assembly Top")
		(33 "B.Fab" user "Ref Des/Assembly Bottom")
	)
	(footprint ""
		(layer "F.Cu")
		(at 122.047 -136.906 90)
		(property "Reference" "PC17"
			(at 6.19633 1.016 0)
			(unlocked yes)
			(layer "F.SilkS")
			(effects
				(font
					(size 0.7874 0.5842)
					(thickness 0.1524)
				)
				(justify left)
			)
		)
		(property "Value" ""
			(at 0 0 90)
			(layer "F.Fab")
			(effects
				(font
					(size 1.27 1.27)
				)
			)
		)
		(duplicate_pad_numbers_are_jumpers no)
		(fp_line
			(start 5.2578 2.499868)
			(end -5.2578 2.499868)
			(stroke
				(width 0.1524)
				(type default)
			)
			(layer "F.SilkS")
		)
		(fp_circle
			(center 0 2.500122)
			(end 0 7.758176)
			(stroke
				(width 0.1524)
				(type default)
			)
			(fill no)
			(layer "F.SilkS")
		)
		(fp_poly
			(pts
				(arc
					(start 5.2578 2.499868)
					(mid 0 7.757922)
					(end -5.2578 2.499868)
				)
			)
			(stroke
				(width 0)
				(type default)
			)
			(fill yes)
			(layer "F.SilkS")
		)
		(fp_circle
			(center 0 2.500122)
			(end 0 7.758176)
			(stroke
				(width 0.1)
				(type default)
			)
			(fill no)
			(layer "F.Fab")
		)
		(pad "1" thru_hole rect
			(at 0 0)
			(size 1.5748 1.5748)
			(drill 1.0668)
			(layers "*.Cu" "*.Mask")
			(remove_unused_layers no)
			(net "P52V_HS_FILTER")
			(clearance 0)
			(padstack
				(mode front_inner_back)
				(layer "Inner"
					(shape circle)
					(size 1.5748 1.5748)
					(clearance 0)
				)
				(layer "B.Cu"
					(shape rect)
					(size 1.5748 1.5748)
					(clearance 0)
				)
			)
		)
		(pad "2" thru_hole circle
			(at 0 4.99999)
			(size 1.5748 1.5748)
			(drill 1.0668)
			(layers "*.Cu" "*.Mask")
			(remove_unused_layers no)
			(net "GND")
			(clearance 0)
		)
	)
	(footprint ""
		(layer "F.Cu")
		(at 219.434918 -113.24717 90)
		(property "Reference" "L1"
			(at -7.703566 5.312918 0)
			(unlocked yes)
			(layer "F.SilkS")
			(effects
				(font
					(size 0.7874 0.5842)
					(thickness 0.1524)
				)
				(justify left)
			)
		)
		(property "Value" ""
			(at 0 0 90)
			(layer "F.Fab")
			(effects
				(font
					(size 1.27 1.27)
				)
			)
		)
		(duplicate_pad_numbers_are_jumpers no)
		(fp_line
			(start 6.849872 -6.450076)
			(end -6.849872 -6.450076)
			(stroke
				(width 0.1524)
				(type default)
			)
			(layer "F.SilkS")
		)
		(fp_line
			(start -6.849872 -6.450076)
			(end -6.849872 -2.6416)
			(stroke
				(width 0.1524)
				(type default)
			)
			(layer "F.SilkS")
		)
		(fp_line
			(start 6.849872 -2.6416)
			(end 6.849872 -6.450076)
			(stroke
				(width 0.1524)
				(type default)
			)
			(layer "F.SilkS")
		)
		(fp_line
			(start -6.849872 2.6416)
			(end -6.849872 6.450076)
			(stroke
				(width 0.1524)
				(type default)
			)
			(layer "F.SilkS")
		)
		(fp_line
			(start 6.849872 6.450076)
			(end 6.849872 2.6416)
			(stroke
				(width 0.1524)
				(type default)
			)
			(layer "F.SilkS")
		)
		(fp_line
			(start -6.849872 6.450076)
			(end 6.849872 6.450076)
			(stroke
				(width 0.1524)
				(type default)
			)
			(layer "F.SilkS")
		)
		(fp_line
			(start 6.849872 -6.450076)
			(end -6.849872 -6.450076)
			(stroke
				(width 0.1)
				(type default)
			)
			(layer "F.Fab")
		)
		(fp_line
			(start -6.849872 -6.450076)
			(end -6.849872 6.450076)
			(stroke
				(width 0.1)
				(type default)
			)
			(layer "F.Fab")
		)
		(fp_line
			(start 6.849872 6.450076)
			(end 6.849872 -6.450076)
			(stroke
				(width 0.1)
				(type default)
			)
			(layer "F.Fab")
		)
		(fp_line
			(start -6.849872 6.450076)
			(end 6.849872 6.450076)
			(stroke
				(width 0.1)
				(type default)
			)
			(layer "F.Fab")
		)
		(pad "1" smd rect
			(at -5.407406 0 90)
			(size 2.9464 5.0038)
			(layers "F.Cu" "F.Mask" "F.Paste")
			(net "P52V_HS")
		)
		(pad "2" smd rect
			(at 5.407406 0 90)
			(size 2.9464 5.0038)
			(layers "F.Cu" "F.Mask" "F.Paste")
			(net "P52V_HS_FILTER")
		)
	)
	(footprint ""
		(layer "F.Cu")
		(at 287.4518 -35.168078)
		(property "Reference" "PR6932"
			(at 0 0 0)
			(layer "F.SilkS")
			(hide yes)
			(effects
				(font
					(size 1.27 1.27)
				)
			)
		)
		(property "Value" ""
			(at 0 0 0)
			(layer "F.Fab")
			(effects
				(font
					(size 1.27 1.27)
				)
			)
		)
		(duplicate_pad_numbers_are_jumpers no)
		(fp_line
			(start -0.7874 -0.4064)
			(end 0.7874 -0.4064)
			(stroke
				(width 0.1524)
				(type default)
			)
			(layer "F.SilkS")
		)
		(fp_line
			(start -0.7874 0.4064)
			(end -0.7874 -0.4064)
			(stroke
				(width 0.1524)
				(type default)
			)
			(layer "F.SilkS")
		)
		(fp_line
			(start 0.7874 -0.4064)
			(end 0.7874 0.4064)
			(stroke
				(width 0.1524)
				(type default)
			)
			(layer "F.SilkS")
		)
		(fp_line
			(start 0.7874 0.4064)
			(end -0.7874 0.4064)
			(stroke
				(width 0.1524)
				(type default)
			)
			(layer "F.SilkS")
		)
		(fp_line
			(start -0.67945 -0.305054)
			(end -0.12065 -0.305054)
			(stroke
				(width 0.1)
				(type default)
			)
			(layer "F.Fab")
		)
		(fp_line
			(start -0.67945 0.3048)
			(end -0.67945 -0.305054)
			(stroke
				(width 0.1)
				(type default)
			)
			(layer "F.Fab")
		)
		(fp_line
			(start -0.12065 -0.305054)
			(end -0.12065 -0.2794)
			(stroke
				(width 0.1)
				(type default)
			)
			(layer "F.Fab")
		)
		(fp_line
			(start -0.12065 -0.2794)
			(end 0.12065 -0.2794)
			(stroke
				(width 0.1)
				(type default)
			)
			(layer "F.Fab")
		)
		(fp_line
			(start -0.12065 0.2794)
			(end -0.12065 0.3048)
			(stroke
				(width 0.1)
				(type default)
			)
			(layer "F.Fab")
		)
		(fp_line
			(start -0.12065 0.3048)
			(end -0.67945 0.3048)
			(stroke
				(width 0.1)
				(type default)
			)
			(layer "F.Fab")
		)
		(fp_line
			(start 0.120396 0.2794)
			(end -0.12065 0.2794)
			(stroke
				(width 0.1)
				(type default)
			)
			(layer "F.Fab")
		)
		(fp_line
			(start 0.120396 0.3048)
			(end 0.120396 0.2794)
			(stroke
				(width 0.1)
				(type default)
			)
			(layer "F.Fab")
		)
		(fp_line
			(start 0.12065 -0.3048)
			(end 0.67945 -0.3048)
			(stroke
				(width 0.1)
				(type default)
			)
			(layer "F.Fab")
		)
		(fp_line
			(start 0.12065 -0.2794)
			(end 0.12065 -0.3048)
			(stroke
				(width 0.1)
				(type default)
			)
			(layer "F.Fab")
		)
		(fp_line
			(start 0.67945 -0.3048)
			(end 0.67945 0.3048)
			(stroke
				(width 0.1)
				(type default)
			)
			(layer "F.Fab")
		)
		(fp_line
			(start 0.67945 0.3048)
			(end 0.120396 0.3048)
			(stroke
				(width 0.1)
				(type default)
			)
			(layer "F.Fab")
		)
		(pad "1" smd circle
			(at -0.40005 0)
			(size 0 0)
			(layers "F.Cu" "F.Mask" "F.Paste")
			(net "P52V_HS1_PWRGIN")
		)
		(pad "2" smd circle
			(at 0.40005 0)
			(size 0 0)
			(layers "F.Cu" "F.Mask" "F.Paste")
			(net "GND_FIELD_SIGNAL")
		)
	)
	(footprint ""
		(layer "F.Cu")
		(at 30.000194 -11.999976 -90)
		(property "Reference" "H16"
			(at 6.692646 12.982194 0)
			(unlocked yes)
			(layer "F.SilkS")
			(effects
				(font
					(size 0.7874 0.5842)
					(thickness 0.1524)
				)
				(justify left)
			)
		)
		(property "Value" ""
			(at 0 0 270)
			(layer "F.Fab")
			(effects
				(font
					(size 1.27 1.27)
				)
			)
		)
		(duplicate_pad_numbers_are_jumpers no)
		(pad "1" thru_hole oval
			(at 0 0 270)
			(size 10.0076 32.004)
			(drill 3.0226
				(offset 0 10.999978)
			)
			(layers "*.Cu" "*.Mask")
			(remove_unused_layers no)
			(net "GND")
			(clearance -1.995678)
			(padstack
				(mode front_inner_back)
				(layer "Inner"
					(shape circle)
					(size 0 0)
					(clearance 0)
				)
				(layer "B.Cu"
					(shape oval)
					(size 10.0076 32.004)
					(offset 0 10.999978)
					(clearance -1.995678)
				)
			)
		)
	)
	(footprint ""
		(layer "F.Cu")
		(at 40.781478 -62.27064)
		(property "Reference" "R5894"
			(at 0 0 0)
			(layer "F.SilkS")
			(hide yes)
			(effects
				(font
					(size 1.27 1.27)
				)
			)
		)
		(property "Value" ""
			(at 0 0 0)
			(layer "F.Fab")
			(effects
				(font
					(size 1.27 1.27)
				)
			)
		)
		(duplicate_pad_numbers_are_jumpers no)
		(fp_line
			(start -0.7874 -0.4064)
			(end 0.7874 -0.4064)
			(stroke
				(width 0.1524)
				(type default)
			)
			(layer "F.SilkS")
		)
		(fp_line
			(start -0.7874 0.4064)
			(end -0.7874 -0.4064)
			(stroke
				(width 0.1524)
				(type default)
			)
			(layer "F.SilkS")
		)
		(fp_line
			(start 0.7874 -0.4064)
			(end 0.7874 0.4064)
			(stroke
				(width 0.1524)
				(type default)
			)
			(layer "F.SilkS")
		)
		(fp_line
			(start 0.7874 0.4064)
			(end -0.7874 0.4064)
			(stroke
				(width 0.1524)
				(type default)
			)
			(layer "F.SilkS")
		)
		(fp_line
			(start -0.67945 -0.305054)
			(end -0.12065 -0.305054)
			(stroke
				(width 0.1)
				(type default)
			)
			(layer "F.Fab")
		)
		(fp_line
			(start -0.67945 0.3048)
			(end -0.67945 -0.305054)
			(stroke
				(width 0.1)
				(type default)
			)
			(layer "F.Fab")
		)
		(fp_line
			(start -0.12065 -0.305054)
			(end -0.12065 -0.2794)
			(stroke
				(width 0.1)
				(type default)
			)
			(layer "F.Fab")
		)
		(fp_line
			(start -0.12065 -0.2794)
			(end 0.12065 -0.2794)
			(stroke
				(width 0.1)
				(type default)
			)
			(layer "F.Fab")
		)
		(fp_line
			(start -0.12065 0.2794)
			(end -0.12065 0.3048)
			(stroke
				(width 0.1)
				(type default)
			)
			(layer "F.Fab")
		)
		(fp_line
			(start -0.12065 0.3048)
			(end -0.67945 0.3048)
			(stroke
				(width 0.1)
				(type default)
			)
			(layer "F.Fab")
		)
		(fp_line
			(start 0.120396 0.2794)
			(end -0.12065 0.2794)
			(stroke
				(width 0.1)
				(type default)
			)
			(layer "F.Fab")
		)
		(fp_line
			(start 0.120396 0.3048)
			(end 0.120396 0.2794)
			(stroke
				(width 0.1)
				(type default)
			)
			(layer "F.Fab")
		)
		(fp_line
			(start 0.12065 -0.3048)
			(end 0.67945 -0.3048)
			(stroke
				(width 0.1)
				(type default)
			)
			(layer "F.Fab")
		)
		(fp_line
			(start 0.12065 -0.2794)
			(end 0.12065 -0.3048)
			(stroke
				(width 0.1)
				(type default)
			)
			(layer "F.Fab")
		)
		(fp_line
			(start 0.67945 -0.3048)
			(end 0.67945 0.3048)
			(stroke
				(width 0.1)
				(type default)
			)
			(layer "F.Fab")
		)
		(fp_line
			(start 0.67945 0.3048)
			(end 0.120396 0.3048)
			(stroke
				(width 0.1)
				(type default)
			)
			(layer "F.Fab")
		)
		(pad "1" smd rect
			(at -0.40005 0 180)
			(size 0.4572 0.508)
			(layers "F.Cu" "F.Mask" "F.Paste")
			(net "P12V_BRICK")
		)
		(pad "2" smd rect
			(at 0.40005 0 180)
			(size 0.4572 0.508)
			(layers "F.Cu" "F.Mask" "F.Paste")
			(net "P12V_HPDB_0_FB")
		)
	)
	(footprint ""
		(layer "F.Cu")
		(at 281.559 -35.687 90)
		(property "Reference" "R150"
			(at 0 0 90)
			(layer "F.SilkS")
			(hide yes)
			(effects
				(font
					(size 1.27 1.27)
				)
			)
		)
		(property "Value" ""
			(at 0 0 90)
			(layer "F.Fab")
			(effects
				(font
					(size 1.27 1.27)
				)
			)
		)
		(duplicate_pad_numbers_are_jumpers no)
		(fp_line
			(start 0.7874 -0.4064)
			(end 0.7874 0.4064)
			(stroke
				(width 0.1524)
				(type default)
			)
			(layer "F.SilkS")
		)
		(fp_line
			(start -0.7874 -0.4064)
			(end 0.7874 -0.4064)
			(stroke
				(width 0.1524)
				(type default)
			)
			(layer "F.SilkS")
		)
		(fp_line
			(start 0.7874 0.4064)
			(end -0.7874 0.4064)
			(stroke
				(width 0.1524)
				(type default)
			)
			(layer "F.SilkS")
		)
		(fp_line
			(start -0.7874 0.4064)
			(end -0.7874 -0.4064)
			(stroke
				(width 0.1524)
				(type default)
			)
			(layer "F.SilkS")
		)
		(fp_line
			(start -0.12065 -0.305054)
			(end -0.12065 -0.2794)
			(stroke
				(width 0.1)
				(type default)
			)
			(layer "F.Fab")
		)
		(fp_line
			(start -0.67945 -0.305054)
			(end -0.12065 -0.305054)
			(stroke
				(width 0.1)
				(type default)
			)
			(layer "F.Fab")
		)
		(fp_line
			(start 0.67945 -0.3048)
			(end 0.67945 0.3048)
			(stroke
				(width 0.1)
				(type default)
			)
			(layer "F.Fab")
		)
		(fp_line
			(start 0.12065 -0.3048)
			(end 0.67945 -0.3048)
			(stroke
				(width 0.1)
				(type default)
			)
			(layer "F.Fab")
		)
		(fp_line
			(start 0.12065 -0.2794)
			(end 0.12065 -0.3048)
			(stroke
				(width 0.1)
				(type default)
			)
			(layer "F.Fab")
		)
		(fp_line
			(start -0.12065 -0.2794)
			(end 0.12065 -0.2794)
			(stroke
				(width 0.1)
				(type default)
			)
			(layer "F.Fab")
		)
		(fp_line
			(start 0.120396 0.2794)
			(end -0.12065 0.2794)
			(stroke
				(width 0.1)
				(type default)
			)
			(layer "F.Fab")
		)
		(fp_line
			(start -0.12065 0.2794)
			(end -0.12065 0.3048)
			(stroke
				(width 0.1)
				(type default)
			)
			(layer "F.Fab")
		)
		(fp_line
			(start 0.67945 0.3048)
			(end 0.120396 0.3048)
			(stroke
				(width 0.1)
				(type default)
			)
			(layer "F.Fab")
		)
		(fp_line
			(start 0.120396 0.3048)
			(end 0.120396 0.2794)
			(stroke
				(width 0.1)
				(type default)
			)
			(layer "F.Fab")
		)
		(fp_line
			(start -0.12065 0.3048)
			(end -0.67945 0.3048)
			(stroke
				(width 0.1)
				(type default)
			)
			(layer "F.Fab")
		)
		(fp_line
			(start -0.67945 0.3048)
			(end -0.67945 -0.305054)
			(stroke
				(width 0.1)
				(type default)
			)
			(layer "F.Fab")
		)
		(pad "1" smd circle
			(at -0.40005 0 90)
			(size 0 0)
			(layers "F.Cu" "F.Mask" "F.Paste")
			(net "P3V3_AUX")
		)
		(pad "2" smd circle
			(at 0.40005 0 90)
			(size 0 0)
			(layers "F.Cu" "F.Mask" "F.Paste")
			(net "P52V_HS1_GPO2")
		)
	)
	(footprint ""
		(layer "F.Cu")
		(at 90.043 -49.911)
		(property "Reference" "PC89"
			(at 0 0 0)
			(layer "F.SilkS")
			(hide yes)
			(effects
				(font
					(size 1.27 1.27)
				)
			)
		)
		(property "Value" ""
			(at 0 0 0)
			(layer "F.Fab")
			(effects
				(font
					(size 1.27 1.27)
				)
			)
		)
		(duplicate_pad_numbers_are_jumpers no)
		(fp_line
			(start -1.524 -0.762)
			(end 1.524 -0.762)
			(stroke
				(width 0.1524)
				(type default)
			)
			(layer "F.SilkS")
		)
		(fp_line
			(start -1.524 0.762)
			(end -1.524 -0.762)
			(stroke
				(width 0.1524)
				(type default)
			)
			(layer "F.SilkS")
		)
		(fp_line
			(start 1.524 -0.762)
			(end 1.524 0.762)
			(stroke
				(width 0.1524)
				(type default)
			)
			(layer "F.SilkS")
		)
		(fp_line
			(start 1.524 0.762)
			(end -1.524 0.762)
			(stroke
				(width 0.1524)
				(type default)
			)
			(layer "F.SilkS")
		)
		(fp_line
			(start -1.1049 -0.724916)
			(end -1.1049 0.724916)
			(stroke
				(width 0.1)
				(type default)
			)
			(layer "F.Fab")
		)
		(fp_line
			(start -1.1049 0.724916)
			(end 1.1049 0.724916)
			(stroke
				(width 0.1)
				(type default)
			)
			(layer "F.Fab")
		)
		(fp_line
			(start 1.1049 -0.724916)
			(end -1.1049 -0.724916)
			(stroke
				(width 0.1)
				(type default)
			)
			(layer "F.Fab")
		)
		(fp_line
			(start 1.1049 0.724916)
			(end 1.1049 -0.724916)
			(stroke
				(width 0.1)
				(type default)
			)
			(layer "F.Fab")
		)
		(pad "1" smd rect
			(at -0.889 0 180)
			(size 1.016 1.27)
			(layers "F.Cu" "F.Mask" "F.Paste")
			(net "P12V_BRICK")
		)
		(pad "2" smd rect
			(at 0.889 0 180)
			(size 1.016 1.27)
			(layers "F.Cu" "F.Mask" "F.Paste")
			(net "GND")
		)
	)
)
